(kicad_pcb
	(version 20260206)
	(generator "pcbnew")
	(generator_version "10.0")
	(general
		(thickness 1.6)
		(legacy_teardrops no)
	)
	(paper "A4")
	(title_block
		(title "03242023_DA0F0TMBIJ0_F0T_Motherboard_J_brd_V01_OCP.brd")
		(comment 1 "Grand Teton / footprints 1906-1911 of 6105")
	)
	(layers
		(0 "F.Cu" signal "TOP")
		(4 "In1.Cu" signal "GND")
		(6 "In2.Cu" signal "IN1")
		(8 "In3.Cu" signal "GND1")
		(10 "In4.Cu" signal "IN2")
		(12 "In5.Cu" signal "GND2")
		(14 "In6.Cu" signal "IN3")
		(16 "In7.Cu" signal "GND3")
		(18 "In8.Cu" signal "VCC")
		(20 "In9.Cu" signal "VCC1")
		(22 "In10.Cu" signal "GND4")
		(24 "In11.Cu" signal "IN4")
		(26 "In12.Cu" signal "GND5")
		(28 "In13.Cu" signal "IN5")
		(30 "In14.Cu" signal "GND6")
		(32 "In15.Cu" signal "IN6")
		(34 "In16.Cu" signal "GND7")
		(2 "B.Cu" signal "BOTTOM")
		(9 "F.Adhes" user "F.Adhesive")
		(11 "B.Adhes" user "B.Adhesive")
		(13 "F.Paste" user "Package Geometry/Pastemask Top")
		(15 "B.Paste" user "Package Geometry/Pastemask Bottom")
		(5 "F.SilkS" user "Ref Des/Silkscreen Top")
		(7 "B.SilkS" user "Ref Des/Silkscreen Bottom")
		(1 "F.Mask" user "Board Geometry/Soldermask Top")
		(3 "B.Mask" user "Board Geometry/Soldermask Bottom")
		(17 "Dwgs.User" user "User.Drawings")
		(19 "Cmts.User" user "User.Comments")
		(21 "Eco1.User" user "User.Eco1")
		(23 "Eco2.User" user "User.Eco2")
		(25 "Edge.Cuts" user "Board Geometry/Outline")
		(27 "Margin" user)
		(31 "F.CrtYd" user "Package Geometry/Place Bound Top")
		(29 "B.CrtYd" user "Package Geometry/Place Bound Bottom")
		(35 "F.Fab" user "Ref Des/Assembly Top")
		(33 "B.Fab" user "Ref Des/Assembly Bottom")
	)
	(footprint ""
		(layer "F.Cu")
		(at 180.77688 -39.969948)
		(property "Reference" "R1396"
			(at 0 0 0)
			(layer "F.SilkS")
			(hide yes)
			(effects
				(font
					(size 1.27 1.27)
				)
			)
		)
		(property "Value" ""
			(at 0 0 0)
			(layer "F.Fab")
			(effects
				(font
					(size 1.27 1.27)
				)
			)
		)
		(duplicate_pad_numbers_are_jumpers no)
		(fp_line
			(start -0.7874 -0.4064)
			(end 0.7874 -0.4064)
			(stroke
				(width 0.1524)
				(type default)
			)
			(layer "F.SilkS")
		)
		(fp_line
			(start -0.7874 0.4064)
			(end -0.7874 -0.4064)
			(stroke
				(width 0.1524)
				(type default)
			)
			(layer "F.SilkS")
		)
		(fp_line
			(start 0.7874 -0.4064)
			(end 0.7874 0.4064)
			(stroke
				(width 0.1524)
				(type default)
			)
			(layer "F.SilkS")
		)
		(fp_line
			(start 0.7874 0.4064)
			(end -0.7874 0.4064)
			(stroke
				(width 0.1524)
				(type default)
			)
			(layer "F.SilkS")
		)
		(fp_line
			(start -0.67945 -0.305054)
			(end -0.12065 -0.305054)
			(stroke
				(width 0.1)
				(type default)
			)
			(layer "F.Fab")
		)
		(fp_line
			(start -0.67945 0.3048)
			(end -0.67945 -0.305054)
			(stroke
				(width 0.1)
				(type default)
			)
			(layer "F.Fab")
		)
		(fp_line
			(start -0.12065 -0.305054)
			(end -0.12065 -0.2794)
			(stroke
				(width 0.1)
				(type default)
			)
			(layer "F.Fab")
		)
		(fp_line
			(start -0.12065 -0.2794)
			(end 0.12065 -0.2794)
			(stroke
				(width 0.1)
				(type default)
			)
			(layer "F.Fab")
		)
		(fp_line
			(start -0.12065 0.2794)
			(end -0.12065 0.3048)
			(stroke
				(width 0.1)
				(type default)
			)
			(layer "F.Fab")
		)
		(fp_line
			(start -0.12065 0.3048)
			(end -0.67945 0.3048)
			(stroke
				(width 0.1)
				(type default)
			)
			(layer "F.Fab")
		)
		(fp_line
			(start 0.120396 0.2794)
			(end -0.12065 0.2794)
			(stroke
				(width 0.1)
				(type default)
			)
			(layer "F.Fab")
		)
		(fp_line
			(start 0.120396 0.3048)
			(end 0.120396 0.2794)
			(stroke
				(width 0.1)
				(type default)
			)
			(layer "F.Fab")
		)
		(fp_line
			(start 0.12065 -0.3048)
			(end 0.67945 -0.3048)
			(stroke
				(width 0.1)
				(type default)
			)
			(layer "F.Fab")
		)
		(fp_line
			(start 0.12065 -0.2794)
			(end 0.12065 -0.3048)
			(stroke
				(width 0.1)
				(type default)
			)
			(layer "F.Fab")
		)
		(fp_line
			(start 0.67945 -0.3048)
			(end 0.67945 0.3048)
			(stroke
				(width 0.1)
				(type default)
			)
			(layer "F.Fab")
		)
		(fp_line
			(start 0.67945 0.3048)
			(end 0.120396 0.3048)
			(stroke
				(width 0.1)
				(type default)
			)
			(layer "F.Fab")
		)
		(pad "1" smd circle
			(at -0.40005 0)
			(size 0 0)
			(layers "F.Cu" "F.Mask" "F.Paste")
			(net "FM_M2_SSD_0_PEDET")
		)
		(pad "2" smd circle
			(at 0.40005 0)
			(size 0 0)
			(layers "F.Cu" "F.Mask" "F.Paste")
			(net "P3V3_AUX")
		)
	)
	(footprint ""
		(layer "F.Cu")
		(at 87.196676 -79.078836)
		(property "Reference" "D99"
			(at -44.30141 38.649402 90)
			(unlocked yes)
			(layer "F.SilkS")
			(effects
				(font
					(size 0.635 0.4064)
					(thickness 0.1524)
				)
				(justify left)
			)
		)
		(property "Value" ""
			(at 0 0 0)
			(layer "F.Fab")
			(effects
				(font
					(size 1.27 1.27)
				)
			)
		)
		(duplicate_pad_numbers_are_jumpers no)
		(fp_line
			(start -0.90678 0.4826)
			(end -0.90678 -0.4699)
			(stroke
				(width 0.1524)
				(type default)
			)
			(layer "F.SilkS")
		)
		(fp_line
			(start -0.89408 -0.4826)
			(end 0.90678 -0.4826)
			(stroke
				(width 0.1524)
				(type default)
			)
			(layer "F.SilkS")
		)
		(fp_line
			(start -0.79248 -0.4826)
			(end 1.03378 -0.4826)
			(stroke
				(width 0.1524)
				(type default)
			)
			(layer "F.SilkS")
		)
		(fp_line
			(start -0.64008 -0.4826)
			(end 1.16078 -0.4826)
			(stroke
				(width 0.1524)
				(type default)
			)
			(layer "F.SilkS")
		)
		(fp_line
			(start 0.90678 -0.4826)
			(end 0.90678 0.4826)
			(stroke
				(width 0.1524)
				(type default)
			)
			(layer "F.SilkS")
		)
		(fp_line
			(start 0.90678 0.4826)
			(end -0.90678 0.4826)
			(stroke
				(width 0.1524)
				(type default)
			)
			(layer "F.SilkS")
		)
		(fp_line
			(start 1.03378 -0.4826)
			(end 1.03378 0.4826)
			(stroke
				(width 0.1524)
				(type default)
			)
			(layer "F.SilkS")
		)
		(fp_line
			(start 1.03378 0.4826)
			(end -0.79248 0.4826)
			(stroke
				(width 0.1524)
				(type default)
			)
			(layer "F.SilkS")
		)
		(fp_line
			(start 1.16078 -0.4826)
			(end 1.16078 0.4826)
			(stroke
				(width 0.1524)
				(type default)
			)
			(layer "F.SilkS")
		)
		(fp_line
			(start 1.16078 0.4826)
			(end -0.64008 0.4826)
			(stroke
				(width 0.1524)
				(type default)
			)
			(layer "F.SilkS")
		)
		(fp_line
			(start -0.499872 -0.249936)
			(end 0.499872 -0.249936)
			(stroke
				(width 0.1)
				(type default)
			)
			(layer "F.Fab")
		)
		(fp_line
			(start -0.499872 0.249936)
			(end -0.499872 -0.249936)
			(stroke
				(width 0.1)
				(type default)
			)
			(layer "F.Fab")
		)
		(fp_line
			(start 0.499872 -0.249936)
			(end 0.499872 0.249936)
			(stroke
				(width 0.1)
				(type default)
			)
			(layer "F.Fab")
		)
		(fp_line
			(start 0.499872 0.249936)
			(end -0.499872 0.249936)
			(stroke
				(width 0.1)
				(type default)
			)
			(layer "F.Fab")
		)
		(pad "A" smd rect
			(at -0.47498 0)
			(size 0.6096 0.7112)
			(layers "F.Cu" "F.Mask" "F.Paste")
			(net "LED_P3V3")
		)
		(pad "C" smd rect
			(at 0.47498 0)
			(size 0.6096 0.7112)
			(layers "F.Cu" "F.Mask" "F.Paste")
			(net "GND")
		)
	)
	(footprint ""
		(layer "F.Cu")
		(at 417.558728 -156.17063 180)
		(property "Reference" "PR1709"
			(at 0 0 180)
			(layer "F.SilkS")
			(hide yes)
			(effects
				(font
					(size 1.27 1.27)
				)
			)
		)
		(property "Value" ""
			(at 0 0 180)
			(layer "F.Fab")
			(effects
				(font
					(size 1.27 1.27)
				)
			)
		)
		(duplicate_pad_numbers_are_jumpers no)
		(fp_line
			(start 0.7874 0.4064)
			(end -0.7874 0.4064)
			(stroke
				(width 0.1524)
				(type default)
			)
			(layer "F.SilkS")
		)
		(fp_line
			(start 0.7874 -0.4064)
			(end 0.7874 0.4064)
			(stroke
				(width 0.1524)
				(type default)
			)
			(layer "F.SilkS")
		)
		(fp_line
			(start -0.7874 0.4064)
			(end -0.7874 -0.4064)
			(stroke
				(width 0.1524)
				(type default)
			)
			(layer "F.SilkS")
		)
		(fp_line
			(start -0.7874 -0.4064)
			(end 0.7874 -0.4064)
			(stroke
				(width 0.1524)
				(type default)
			)
			(layer "F.SilkS")
		)
		(fp_line
			(start 0.67945 0.3048)
			(end 0.120396 0.3048)
			(stroke
				(width 0.1)
				(type default)
			)
			(layer "F.Fab")
		)
		(fp_line
			(start 0.67945 -0.3048)
			(end 0.67945 0.3048)
			(stroke
				(width 0.1)
				(type default)
			)
			(layer "F.Fab")
		)
		(fp_line
			(start 0.12065 -0.2794)
			(end 0.12065 -0.3048)
			(stroke
				(width 0.1)
				(type default)
			)
			(layer "F.Fab")
		)
		(fp_line
			(start 0.12065 -0.3048)
			(end 0.67945 -0.3048)
			(stroke
				(width 0.1)
				(type default)
			)
			(layer "F.Fab")
		)
		(fp_line
			(start 0.120396 0.3048)
			(end 0.120396 0.2794)
			(stroke
				(width 0.1)
				(type default)
			)
			(layer "F.Fab")
		)
		(fp_line
			(start 0.120396 0.2794)
			(end -0.12065 0.2794)
			(stroke
				(width 0.1)
				(type default)
			)
			(layer "F.Fab")
		)
		(fp_line
			(start -0.12065 0.3048)
			(end -0.67945 0.3048)
			(stroke
				(width 0.1)
				(type default)
			)
			(layer "F.Fab")
		)
		(fp_line
			(start -0.12065 0.2794)
			(end -0.12065 0.3048)
			(stroke
				(width 0.1)
				(type default)
			)
			(layer "F.Fab")
		)
		(fp_line
			(start -0.12065 -0.2794)
			(end 0.12065 -0.2794)
			(stroke
				(width 0.1)
				(type default)
			)
			(layer "F.Fab")
		)
		(fp_line
			(start -0.12065 -0.305054)
			(end -0.12065 -0.2794)
			(stroke
				(width 0.1)
				(type default)
			)
			(layer "F.Fab")
		)
		(fp_line
			(start -0.67945 0.3048)
			(end -0.67945 -0.305054)
			(stroke
				(width 0.1)
				(type default)
			)
			(layer "F.Fab")
		)
		(fp_line
			(start -0.67945 -0.305054)
			(end -0.12065 -0.305054)
			(stroke
				(width 0.1)
				(type default)
			)
			(layer "F.Fab")
		)
		(pad "1" smd circle
			(at -0.40005 0 180)
			(size 0 0)
			(layers "F.Cu" "F.Mask" "F.Paste")
			(net "PVCCFA_EHV_CPU0_LSET1")
		)
		(pad "2" smd circle
			(at 0.40005 0 180)
			(size 0 0)
			(layers "F.Cu" "F.Mask" "F.Paste")
			(net "GND")
		)
	)
	(footprint ""
		(layer "F.Cu")
		(at 164.64788 -118.836948)
		(property "Reference" "R3324"
			(at 0 0 0)
			(layer "F.SilkS")
			(hide yes)
			(effects
				(font
					(size 1.27 1.27)
				)
			)
		)
		(property "Value" ""
			(at 0 0 0)
			(layer "F.Fab")
			(effects
				(font
					(size 1.27 1.27)
				)
			)
		)
		(duplicate_pad_numbers_are_jumpers no)
		(fp_line
			(start -0.7874 -0.4064)
			(end 0.7874 -0.4064)
			(stroke
				(width 0.1524)
				(type default)
			)
			(layer "F.SilkS")
		)
		(fp_line
			(start -0.7874 0.4064)
			(end -0.7874 -0.4064)
			(stroke
				(width 0.1524)
				(type default)
			)
			(layer "F.SilkS")
		)
		(fp_line
			(start 0.7874 -0.4064)
			(end 0.7874 0.4064)
			(stroke
				(width 0.1524)
				(type default)
			)
			(layer "F.SilkS")
		)
		(fp_line
			(start 0.7874 0.4064)
			(end -0.7874 0.4064)
			(stroke
				(width 0.1524)
				(type default)
			)
			(layer "F.SilkS")
		)
		(fp_line
			(start -0.67945 -0.305054)
			(end -0.12065 -0.305054)
			(stroke
				(width 0.1)
				(type default)
			)
			(layer "F.Fab")
		)
		(fp_line
			(start -0.67945 0.3048)
			(end -0.67945 -0.305054)
			(stroke
				(width 0.1)
				(type default)
			)
			(layer "F.Fab")
		)
		(fp_line
			(start -0.12065 -0.305054)
			(end -0.12065 -0.2794)
			(stroke
				(width 0.1)
				(type default)
			)
			(layer "F.Fab")
		)
		(fp_line
			(start -0.12065 -0.2794)
			(end 0.12065 -0.2794)
			(stroke
				(width 0.1)
				(type default)
			)
			(layer "F.Fab")
		)
		(fp_line
			(start -0.12065 0.2794)
			(end -0.12065 0.3048)
			(stroke
				(width 0.1)
				(type default)
			)
			(layer "F.Fab")
		)
		(fp_line
			(start -0.12065 0.3048)
			(end -0.67945 0.3048)
			(stroke
				(width 0.1)
				(type default)
			)
			(layer "F.Fab")
		)
		(fp_line
			(start 0.120396 0.2794)
			(end -0.12065 0.2794)
			(stroke
				(width 0.1)
				(type default)
			)
			(layer "F.Fab")
		)
		(fp_line
			(start 0.120396 0.3048)
			(end 0.120396 0.2794)
			(stroke
				(width 0.1)
				(type default)
			)
			(layer "F.Fab")
		)
		(fp_line
			(start 0.12065 -0.3048)
			(end 0.67945 -0.3048)
			(stroke
				(width 0.1)
				(type default)
			)
			(layer "F.Fab")
		)
		(fp_line
			(start 0.12065 -0.2794)
			(end 0.12065 -0.3048)
			(stroke
				(width 0.1)
				(type default)
			)
			(layer "F.Fab")
		)
		(fp_line
			(start 0.67945 -0.3048)
			(end 0.67945 0.3048)
			(stroke
				(width 0.1)
				(type default)
			)
			(layer "F.Fab")
		)
		(fp_line
			(start 0.67945 0.3048)
			(end 0.120396 0.3048)
			(stroke
				(width 0.1)
				(type default)
			)
			(layer "F.Fab")
		)
		(pad "1" smd circle
			(at -0.40005 0)
			(size 0 0)
			(layers "F.Cu" "F.Mask" "F.Paste")
			(net "GPU_FPGA_READY_ISO")
		)
		(pad "2" smd circle
			(at 0.40005 0)
			(size 0 0)
			(layers "F.Cu" "F.Mask" "F.Paste")
			(net "GPU_FPGA_READY_ISO_R")
		)
	)
	(footprint ""
		(layer "F.Cu")
		(at 20.831556 -178.077368 -90)
		(property "Reference" "PR2222"
			(at 0 0 270)
			(layer "F.SilkS")
			(hide yes)
			(effects
				(font
					(size 1.27 1.27)
				)
			)
		)
		(property "Value" ""
			(at 0 0 270)
			(layer "F.Fab")
			(effects
				(font
					(size 1.27 1.27)
				)
			)
		)
		(duplicate_pad_numbers_are_jumpers no)
		(fp_line
			(start -0.7874 0.4064)
			(end -0.7874 -0.4064)
			(stroke
				(width 0.1524)
				(type default)
			)
			(layer "F.SilkS")
		)
		(fp_line
			(start 0.7874 0.4064)
			(end -0.7874 0.4064)
			(stroke
				(width 0.1524)
				(type default)
			)
			(layer "F.SilkS")
		)
		(fp_line
			(start -0.7874 -0.4064)
			(end 0.7874 -0.4064)
			(stroke
				(width 0.1524)
				(type default)
			)
			(layer "F.SilkS")
		)
		(fp_line
			(start 0.7874 -0.4064)
			(end 0.7874 0.4064)
			(stroke
				(width 0.1524)
				(type default)
			)
			(layer "F.SilkS")
		)
		(fp_line
			(start -0.67945 0.3048)
			(end -0.67945 -0.305054)
			(stroke
				(width 0.1)
				(type default)
			)
			(layer "F.Fab")
		)
		(fp_line
			(start -0.12065 0.3048)
			(end -0.67945 0.3048)
			(stroke
				(width 0.1)
				(type default)
			)
			(layer "F.Fab")
		)
		(fp_line
			(start 0.120396 0.3048)
			(end 0.120396 0.2794)
			(stroke
				(width 0.1)
				(type default)
			)
			(layer "F.Fab")
		)
		(fp_line
			(start 0.67945 0.3048)
			(end 0.120396 0.3048)
			(stroke
				(width 0.1)
				(type default)
			)
			(layer "F.Fab")
		)
		(fp_line
			(start -0.12065 0.2794)
			(end -0.12065 0.3048)
			(stroke
				(width 0.1)
				(type default)
			)
			(layer "F.Fab")
		)
		(fp_line
			(start 0.120396 0.2794)
			(end -0.12065 0.2794)
			(stroke
				(width 0.1)
				(type default)
			)
			(layer "F.Fab")
		)
		(fp_line
			(start -0.12065 -0.2794)
			(end 0.12065 -0.2794)
			(stroke
				(width 0.1)
				(type default)
			)
			(layer "F.Fab")
		)
		(fp_line
			(start 0.12065 -0.2794)
			(end 0.12065 -0.3048)
			(stroke
				(width 0.1)
				(type default)
			)
			(layer "F.Fab")
		)
		(fp_line
			(start 0.12065 -0.3048)
			(end 0.67945 -0.3048)
			(stroke
				(width 0.1)
				(type default)
			)
			(layer "F.Fab")
		)
		(fp_line
			(start 0.67945 -0.3048)
			(end 0.67945 0.3048)
			(stroke
				(width 0.1)
				(type default)
			)
			(layer "F.Fab")
		)
		(fp_line
			(start -0.67945 -0.305054)
			(end -0.12065 -0.305054)
			(stroke
				(width 0.1)
				(type default)
			)
			(layer "F.Fab")
		)
		(fp_line
			(start -0.12065 -0.305054)
			(end -0.12065 -0.2794)
			(stroke
				(width 0.1)
				(type default)
			)
			(layer "F.Fab")
		)
		(pad "1" smd circle
			(at -0.40005 0 270)
			(size 0 0)
			(layers "F.Cu" "F.Mask" "F.Paste")
			(net "PVNN_MAIN_CPU1_CS")
		)
		(pad "2" smd circle
			(at 0.40005 0 270)
			(size 0 0)
			(layers "F.Cu" "F.Mask" "F.Paste")
			(net "GND")
		)
	)
	(footprint ""
		(layer "F.Cu")
		(at 27.81681 -55.015384)
		(property "Reference" "R3051"
			(at 0 0 0)
			(layer "F.SilkS")
			(hide yes)
			(effects
				(font
					(size 1.27 1.27)
				)
			)
		)
		(property "Value" ""
			(at 0 0 0)
			(layer "F.Fab")
			(effects
				(font
					(size 1.27 1.27)
				)
			)
		)
		(duplicate_pad_numbers_are_jumpers no)
		(fp_line
			(start -0.7874 -0.4064)
			(end 0.7874 -0.4064)
			(stroke
				(width 0.1524)
				(type default)
			)
			(layer "F.SilkS")
		)
		(fp_line
			(start -0.7874 0.4064)
			(end -0.7874 -0.4064)
			(stroke
				(width 0.1524)
				(type default)
			)
			(layer "F.SilkS")
		)
		(fp_line
			(start 0.7874 -0.4064)
			(end 0.7874 0.4064)
			(stroke
				(width 0.1524)
				(type default)
			)
			(layer "F.SilkS")
		)
		(fp_line
			(start 0.7874 0.4064)
			(end -0.7874 0.4064)
			(stroke
				(width 0.1524)
				(type default)
			)
			(layer "F.SilkS")
		)
		(fp_line
			(start -0.67945 -0.305054)
			(end -0.12065 -0.305054)
			(stroke
				(width 0.1)
				(type default)
			)
			(layer "F.Fab")
		)
		(fp_line
			(start -0.67945 0.3048)
			(end -0.67945 -0.305054)
			(stroke
				(width 0.1)
				(type default)
			)
			(layer "F.Fab")
		)
		(fp_line
			(start -0.12065 -0.305054)
			(end -0.12065 -0.2794)
			(stroke
				(width 0.1)
				(type default)
			)
			(layer "F.Fab")
		)
		(fp_line
			(start -0.12065 -0.2794)
			(end 0.12065 -0.2794)
			(stroke
				(width 0.1)
				(type default)
			)
			(layer "F.Fab")
		)
		(fp_line
			(start -0.12065 0.2794)
			(end -0.12065 0.3048)
			(stroke
				(width 0.1)
				(type default)
			)
			(layer "F.Fab")
		)
		(fp_line
			(start -0.12065 0.3048)
			(end -0.67945 0.3048)
			(stroke
				(width 0.1)
				(type default)
			)
			(layer "F.Fab")
		)
		(fp_line
			(start 0.120396 0.2794)
			(end -0.12065 0.2794)
			(stroke
				(width 0.1)
				(type default)
			)
			(layer "F.Fab")
		)
		(fp_line
			(start 0.120396 0.3048)
			(end 0.120396 0.2794)
			(stroke
				(width 0.1)
				(type default)
			)
			(layer "F.Fab")
		)
		(fp_line
			(start 0.12065 -0.3048)
			(end 0.67945 -0.3048)
			(stroke
				(width 0.1)
				(type default)
			)
			(layer "F.Fab")
		)
		(fp_line
			(start 0.12065 -0.2794)
			(end 0.12065 -0.3048)
			(stroke
				(width 0.1)
				(type default)
			)
			(layer "F.Fab")
		)
		(fp_line
			(start 0.67945 -0.3048)
			(end 0.67945 0.3048)
			(stroke
				(width 0.1)
				(type default)
			)
			(layer "F.Fab")
		)
		(fp_line
			(start 0.67945 0.3048)
			(end 0.120396 0.3048)
			(stroke
				(width 0.1)
				(type default)
			)
			(layer "F.Fab")
		)
		(pad "1" smd circle
			(at -0.40005 0)
			(size 0 0)
			(layers "F.Cu" "F.Mask" "F.Paste")
			(net "IRQ_SML1_PMBUS_ALERT_R_N")
		)
		(pad "2" smd circle
			(at 0.40005 0)
			(size 0 0)
			(layers "F.Cu" "F.Mask" "F.Paste")
			(net "IRQ_SML1_PMBUS_ALERT_N")
		)
	)
)
